# S9S_MB_2U (Grand Teton) — schematic netlist excerpt (pin names and nets, part order shuffled) for the footprints in the layout excerpt that follows; sources: Cadence DE-HDL packaged netlist, KiCad conversion of 03242023_DA0F0TMBIJ0_F0T_Motherboard_J_brd_V01_OCP.brd

R854  Q_RES  0 5% CHIP  pkg 0402LF  page 128 : A = RST_CPU0_DRAM_GH_N ; B = RST_CPU0_DRAM_GH_PLD_N
C1340  Q_CAP  10UF 16V 10% X6S  pkg C0805  page 260 : A = P3V3 ; B = GND
PC2103  Q_CAP  1UF 25V 10% X6S  pkg C0402  page 301 : A = HSC_VDD18 ; B = AGND_HSC

(kicad_pcb
	(version 20260206)
	(generator "pcbnew")
	(generator_version "10.0")
	(general
		(thickness 1.6)
		(legacy_teardrops no)
	)
	(paper "A4")
	(title_block
		(title "03242023_DA0F0TMBIJ0_F0T_Motherboard_J_brd_V01_OCP.brd")
		(comment 1 "Grand Teton / footprints 3449-3451 of 6105")
	)
	(layers
		(0 "F.Cu" signal "TOP")
		(4 "In1.Cu" signal "GND")
		(6 "In2.Cu" signal "IN1")
		(8 "In3.Cu" signal "GND1")
		(10 "In4.Cu" signal "IN2")
		(12 "In5.Cu" signal "GND2")
		(14 "In6.Cu" signal "IN3")
		(16 "In7.Cu" signal "GND3")
		(18 "In8.Cu" signal "VCC")
		(20 "In9.Cu" signal "VCC1")
		(22 "In10.Cu" signal "GND4")
		(24 "In11.Cu" signal "IN4")
		(26 "In12.Cu" signal "GND5")
		(28 "In13.Cu" signal "IN5")
		(30 "In14.Cu" signal "GND6")
		(32 "In15.Cu" signal "IN6")
		(34 "In16.Cu" signal "GND7")
		(2 "B.Cu" signal "BOTTOM")
		(9 "F.Adhes" user "F.Adhesive")
		(11 "B.Adhes" user "B.Adhesive")
		(13 "F.Paste" user "Package Geometry/Pastemask Top")
		(15 "B.Paste" user "Package Geometry/Pastemask Bottom")
		(5 "F.SilkS" user "Ref Des/Silkscreen Top")
		(7 "B.SilkS" user "Ref Des/Silkscreen Bottom")
		(1 "F.Mask" user "Board Geometry/Soldermask Top")
		(3 "B.Mask" user "Board Geometry/Soldermask Bottom")
		(17 "Dwgs.User" user "User.Drawings")
		(19 "Cmts.User" user "User.Comments")
		(21 "Eco1.User" user "User.Eco1")
		(23 "Eco2.User" user "User.Eco2")
		(25 "Edge.Cuts" user "Board Geometry/Outline")
		(27 "Margin" user)
		(31 "F.CrtYd" user "Package Geometry/Place Bound Top")
		(29 "B.CrtYd" user "Package Geometry/Place Bound Bottom")
		(35 "F.Fab" user "Ref Des/Assembly Top")
		(33 "B.Fab" user "Ref Des/Assembly Bottom")
	)
	(footprint ""
		(layer "F.Cu")
		(at 117.22608 -119.846598 -90)
		(property "Reference" "R854"
			(at 0 0 270)
			(layer "F.SilkS")
			(hide yes)
			(effects
				(font
					(size 1.27 1.27)
				)
			)
		)
		(property "Value" ""
			(at 0 0 270)
			(layer "F.Fab")
			(effects
				(font
					(size 1.27 1.27)
				)
			)
		)
		(duplicate_pad_numbers_are_jumpers no)
		(fp_line
			(start -0.7874 0.4064)
			(end -0.7874 -0.4064)
			(stroke
				(width 0.1524)
				(type default)
			)
			(layer "F.SilkS")
		)
		(fp_line
			(start 0.7874 0.4064)
			(end -0.7874 0.4064)
			(stroke
				(width 0.1524)
				(type default)
			)
			(layer "F.SilkS")
		)
		(fp_line
			(start -0.7874 -0.4064)
			(end 0.7874 -0.4064)
			(stroke
				(width 0.1524)
				(type default)
			)
			(layer "F.SilkS")
		)
		(fp_line
			(start 0.7874 -0.4064)
			(end 0.7874 0.4064)
			(stroke
				(width 0.1524)
				(type default)
			)
			(layer "F.SilkS")
		)
		(fp_line
			(start -0.67945 0.3048)
			(end -0.67945 -0.305054)
			(stroke
				(width 0.1)
				(type default)
			)
			(layer "F.Fab")
		)
		(fp_line
			(start -0.12065 0.3048)
			(end -0.67945 0.3048)
			(stroke
				(width 0.1)
				(type default)
			)
			(layer "F.Fab")
		)
		(fp_line
			(start 0.120396 0.3048)
			(end 0.120396 0.2794)
			(stroke
				(width 0.1)
				(type default)
			)
			(layer "F.Fab")
		)
		(fp_line
			(start 0.67945 0.3048)
			(end 0.120396 0.3048)
			(stroke
				(width 0.1)
				(type default)
			)
			(layer "F.Fab")
		)
		(fp_line
			(start -0.12065 0.2794)
			(end -0.12065 0.3048)
			(stroke
				(width 0.1)
				(type default)
			)
			(layer "F.Fab")
		)
		(fp_line
			(start 0.120396 0.2794)
			(end -0.12065 0.2794)
			(stroke
				(width 0.1)
				(type default)
			)
			(layer "F.Fab")
		)
		(fp_line
			(start -0.12065 -0.2794)
			(end 0.12065 -0.2794)
			(stroke
				(width 0.1)
				(type default)
			)
			(layer "F.Fab")
		)
		(fp_line
			(start 0.12065 -0.2794)
			(end 0.12065 -0.3048)
			(stroke
				(width 0.1)
				(type default)
			)
			(layer "F.Fab")
		)
		(fp_line
			(start 0.12065 -0.3048)
			(end 0.67945 -0.3048)
			(stroke
				(width 0.1)
				(type default)
			)
			(layer "F.Fab")
		)
		(fp_line
			(start 0.67945 -0.3048)
			(end 0.67945 0.3048)
			(stroke
				(width 0.1)
				(type default)
			)
			(layer "F.Fab")
		)
		(fp_line
			(start -0.67945 -0.305054)
			(end -0.12065 -0.305054)
			(stroke
				(width 0.1)
				(type default)
			)
			(layer "F.Fab")
		)
		(fp_line
			(start -0.12065 -0.305054)
			(end -0.12065 -0.2794)
			(stroke
				(width 0.1)
				(type default)
			)
			(layer "F.Fab")
		)
		(pad "1" smd circle
			(at -0.40005 0 270)
			(size 0 0)
			(layers "F.Cu" "F.Mask" "F.Paste")
			(net "RST_CPU0_DRAM_GH_N")
		)
		(pad "2" smd circle
			(at 0.40005 0 270)
			(size 0 0)
			(layers "F.Cu" "F.Mask" "F.Paste")
			(net "RST_CPU0_DRAM_GH_PLD_N")
		)
	)
	(footprint ""
		(layer "F.Cu")
		(at 431.33518 -58.034428 90)
		(property "Reference" "C1340"
			(at 0 0 90)
			(layer "F.SilkS")
			(hide yes)
			(effects
				(font
					(size 1.27 1.27)
				)
			)
		)
		(property "Value" ""
			(at 0 0 90)
			(layer "F.Fab")
			(effects
				(font
					(size 1.27 1.27)
				)
			)
		)
		(duplicate_pad_numbers_are_jumpers no)
		(fp_line
			(start 1.524 -0.762)
			(end 1.524 0.762)
			(stroke
				(width 0.1524)
				(type default)
			)
			(layer "F.SilkS")
		)
		(fp_line
			(start -1.524 -0.762)
			(end 1.524 -0.762)
			(stroke
				(width 0.1524)
				(type default)
			)
			(layer "F.SilkS")
		)
		(fp_line
			(start 1.524 0.762)
			(end -1.524 0.762)
			(stroke
				(width 0.1524)
				(type default)
			)
			(layer "F.SilkS")
		)
		(fp_line
			(start -1.524 0.762)
			(end -1.524 -0.762)
			(stroke
				(width 0.1524)
				(type default)
			)
			(layer "F.SilkS")
		)
		(fp_line
			(start 1.1049 -0.724916)
			(end -1.1049 -0.724916)
			(stroke
				(width 0.1)
				(type default)
			)
			(layer "F.Fab")
		)
		(fp_line
			(start -1.1049 -0.724916)
			(end -1.1049 0.724916)
			(stroke
				(width 0.1)
				(type default)
			)
			(layer "F.Fab")
		)
		(fp_line
			(start 1.1049 0.724916)
			(end 1.1049 -0.724916)
			(stroke
				(width 0.1)
				(type default)
			)
			(layer "F.Fab")
		)
		(fp_line
			(start -1.1049 0.724916)
			(end 1.1049 0.724916)
			(stroke
				(width 0.1)
				(type default)
			)
			(layer "F.Fab")
		)
		(pad "1" smd rect
			(at -0.889 0 270)
			(size 1.016 1.27)
			(layers "F.Cu" "F.Mask" "F.Paste")
			(net "P3V3")
		)
		(pad "2" smd rect
			(at 0.889 0 270)
			(size 1.016 1.27)
			(layers "F.Cu" "F.Mask" "F.Paste")
			(net "GND")
		)
	)
	(footprint ""
		(layer "F.Cu")
		(at 179.352448 -401.239482 180)
		(property "Reference" "PC2103"
			(at 0 0 180)
			(layer "F.SilkS")
			(hide yes)
			(effects
				(font
					(size 1.27 1.27)
				)
			)
		)
		(property "Value" ""
			(at 0 0 180)
			(layer "F.Fab")
			(effects
				(font
					(size 1.27 1.27)
				)
			)
		)
		(duplicate_pad_numbers_are_jumpers no)
		(fp_line
			(start 0.7874 0.4064)
			(end -0.7874 0.4064)
			(stroke
				(width 0.1524)
				(type default)
			)
			(layer "F.SilkS")
		)
		(fp_line
			(start 0.7874 -0.4064)
			(end 0.7874 0.4064)
			(stroke
				(width 0.1524)
				(type default)
			)
			(layer "F.SilkS")
		)
		(fp_line
			(start -0.7874 0.4064)
			(end -0.7874 -0.4064)
			(stroke
				(width 0.1524)
				(type default)
			)
			(layer "F.SilkS")
		)
		(fp_line
			(start -0.7874 -0.4064)
			(end 0.7874 -0.4064)
			(stroke
				(width 0.1524)
				(type default)
			)
			(layer "F.SilkS")
		)
		(fp_line
			(start 0.67945 0.3048)
			(end 0.120396 0.3048)
			(stroke
				(width 0.1)
				(type default)
			)
			(layer "F.Fab")
		)
		(fp_line
			(start 0.67945 -0.3048)
			(end 0.67945 0.3048)
			(stroke
				(width 0.1)
				(type default)
			)
			(layer "F.Fab")
		)
		(fp_line
			(start 0.12065 -0.2794)
			(end 0.12065 -0.3048)
			(stroke
				(width 0.1)
				(type default)
			)
			(layer "F.Fab")
		)
		(fp_line
			(start 0.12065 -0.3048)
			(end 0.67945 -0.3048)
			(stroke
				(width 0.1)
				(type default)
			)
			(layer "F.Fab")
		)
		(fp_line
			(start 0.120396 0.3048)
			(end 0.120396 0.2794)
			(stroke
				(width 0.1)
				(type default)
			)
			(layer "F.Fab")
		)
		(fp_line
			(start 0.120396 0.2794)
			(end -0.12065 0.2794)
			(stroke
				(width 0.1)
				(type default)
			)
			(layer "F.Fab")
		)
		(fp_line
			(start -0.12065 0.3048)
			(end -0.67945 0.3048)
			(stroke
				(width 0.1)
				(type default)
			)
			(layer "F.Fab")
		)
		(fp_line
			(start -0.12065 0.2794)
			(end -0.12065 0.3048)
			(stroke
				(width 0.1)
				(type default)
			)
			(layer "F.Fab")
		)
		(fp_line
			(start -0.12065 -0.2794)
			(end 0.12065 -0.2794)
			(stroke
				(width 0.1)
				(type default)
			)
			(layer "F.Fab")
		)
		(fp_line
			(start -0.12065 -0.305054)
			(end -0.12065 -0.2794)
			(stroke
				(width 0.1)
				(type default)
			)
			(layer "F.Fab")
		)
		(fp_line
			(start -0.67945 0.3048)
			(end -0.67945 -0.305054)
			(stroke
				(width 0.1)
				(type default)
			)
			(layer "F.Fab")
		)
		(fp_line
			(start -0.67945 -0.305054)
			(end -0.12065 -0.305054)
			(stroke
				(width 0.1)
				(type default)
			)
			(layer "F.Fab")
		)
		(pad "1" smd circle
			(at -0.40005 0 180)
			(size 0 0)
			(layers "F.Cu" "F.Mask" "F.Paste")
			(net "HSC_VDD18")
		)
		(pad "2" smd circle
			(at 0.40005 0 180)
			(size 0 0)
			(layers "F.Cu" "F.Mask" "F.Paste")
			(net "AGND_HSC")
		)
	)
)
